FILE_TYPE = CONNECTIVITY;
{Allegro Design Entry HDL 16.6-p007 (v16-6-112F) 10/10/2012}
"PAGE_NUMBER" = 239;
0"NC";
1"GND\g";
2"P3V3_STBY\g";
3"GND\g";
4"GND\g";
5"GND\g";
6"GND\g";
7"P3V3_STBY\g";
8"GND\g";
9"GND\g";
10"P3V3_STBY\g";
11"P3V3_STBY\g";
12"GND\g";
13"GND\g";
14"GND\g";
15"GND\g";
16"GND\g";
17"GND\g";
18"P2V5_AUX_BMC\g";
19"P1V2_AUX_BMC\g"VOLTAGE"1.5";
20"GND\g";
21"PWRGD_P3V3_STBY";
22"UN$239$CAP$I84$A";
23"UN$239$21K5R2F-GP$I99$2";
24"UN$239$OFFPAGE$I76$A";
25"VR_P1V538_BMC_STBY_FB";
26"PWRGD_P3V3_STBY";
27"PWRGD_P1V538_BMC_STBY_R";
28"PWRGD_P1V538_BMC_STBY";
%"CAP"
"1","(10875,3625)","0","mstr_discrete","I12";
;
CDS_SEC"1"
TOLERANCE"20%"
PACK_TYPE"0603"
VALUE"10UF"
MATERIAL"X6S"
PART_NUMBER"E15431-002"
VOLTAGE"6.3V"
LOCATION"C1T15"
CDS_LOCATION"C1T15"
CDS_LIB"mstr_discrete"
SEC"1"
SEC_TYPE"0603"
ROOM"P1V538_BMC_STBY_VR"
BOM_COST"P1V538_BMC_STBY_VR";
"A"
$PN"1"19;
"B"
$PN"2"15;
%"RES"
"1","(10350,3125)","1","mstr_discrete","I15";
;
CDS_SEC"1"
LOCATION"R9F32"
WATTAGE"1/16W"
PART_NUMBER"G21796-221"
P1V5_STBY_IBMC""
P1V5_STBY_IBMC_VR""
VALUE"13K"
TOLERANCE"1.0%"
MATERIAL"CHIP"
PACK_TYPE"0402"
SEC_TYPE"0402"
BOM_COST"P1V538_BMC_STBY_VR"
SEC"1"
CDS_LOCATION"R9F32"
ROOM"P1V538_BMC_STBY_VR"
CDS_LIB"mstr_discrete";
"B"
$PN"2"25;
"A"
$PN"1"1;
%"GND"
"1","(10350,2900)","0","mstr_symbols","I16";
;
P1V5_STBY_IBMC""
P1V5_STBY_IBMC_VR""
BOM_COST"P1V538_BMC_STBY_VR"
CDS_LIB"mstr_symbols"
SIZE"1B"
VOLTAGE"0.0V"
ROOM"P1V538_BMC_STBY_VR"
BODY_TYPE"PLUMBING"
HDL_POWER"GND";
"A\NAC"1;
%"CAP"
"1","(6525,4150)","0","mstr_discrete","I22";
;
CDS_SEC"1"
LOCATION"C1T7"
VALUE"10UF"
VOLTAGE"6.3V"
TOLERANCE"20%"
PART_NUMBER"E15431-002"
PACK_TYPE"0603"
MATERIAL"X6S"
CDS_LIB"mstr_discrete"
CDS_LOCATION"C1T7"
SEC"1"
SEC_TYPE"0603"
ROOM"P1V538_BMC_STBY_VR"
BOM_COST"P1V538_BMC_STBY_VR";
"A"
$PN"1"7;
"B"
$PN"2"4;
%"CAP"
"1","(7050,3300)","2","mstr_discrete","I30";
;
TOLERANCE"10%"
VOLTAGE"50V"
LOCATION"C9F6"
VALUE"1000PF"
MATERIAL"EMPTY"
PACK_TYPE"0402LF"
PART_NUMBER"A36096-046"
CDS_SEC"1"
CDS_LIB"mstr_discrete"
CDS_LOCATION"C9F6"
$SEC"1"
ROOM"P1V538_BMC_STBY_VR"
BOM_COST"P1V538_BMC_STBY_VR";
"A"
$PN"1"26;
"B"
$PN"2"3;
%"P3V3_STBY"
"1","(9625,5000)","0","mstr_symbols","I35";
;
CDS_LIB"mstr_symbols"
SIZE"1B"
VOLTAGE"3.3V"
BODY_TYPE"PLUMBING"
HDL_POWER"P3V3_STBY";
"G\NAC"2;
%"GND"
"1","(7050,2875)","0","mstr_symbols","I38";
;
P1V5_STBY_IBMC""
P1V5_STBY_IBMC_VR""
CDS_LIB"mstr_symbols"
BOM_COST"P1V538_BMC_STBY_VR"
VOLTAGE"0.0V"
SIZE"1B"
ROOM"P1V538_BMC_STBY_VR"
BODY_TYPE"PLUMBING"
HDL_POWER"GND";
"A\NAC"3;
%"GND"
"1","(6525,3850)","0","mstr_symbols","I39";
;
CDS_LIB"mstr_symbols"
SIZE"1B"
VOLTAGE"0.0V"
BODY_TYPE"PLUMBING"
HDL_POWER"GND";
"A\NAC"4;
%"CAP"
"1","(10375,4150)","0","mstr_discrete","I4";
;
VALUE"1000PF"
PACK_TYPE"0402LF"
LOCATION"C9F10"
TOLERANCE"10%"
MATERIAL"X7R"
PART_NUMBER"A36096-046"
CDS_SEC"1"
CDS_LIB"mstr_discrete"
CDS_LOCATION"C9F10"
$SEC"1"
VOLTAGE"50V"
BOM_COST"P1V538_BMC_STBY_VR"
ROOM"P1V538_BMC_STBY_VR";
"A"
$PN"1"27;
"B"
$PN"2"5;
%"GND"
"1","(10375,3975)","0","mstr_symbols","I5";
;
CDS_LIB"mstr_symbols"
BOM_COST"P1V538_BMC_STBY_VR"
SIZE"1B"
VOLTAGE"0.0V"
ROOM"P1V538_BMC_STBY_VR"
BODY_TYPE"PLUMBING"
HDL_POWER"GND";
"A\NAC"5;
%"RES"
"2","(9625,4525)","0","mstr_discrete","I6";
;
CDS_SEC"1"
PART_NUMBER"G21796-016"
P1V5_STBY_IBMC""
P1V5_STBY_IBMC_VR""
LOCATION"R9F12"
WATTAGE"1/16W"
VALUE"10.0K"
MATERIAL"CHIP"
PACK_TYPE"0402"
TOLERANCE"1%"
CDS_LOCATION"R9F12"
CDS_LIB"mstr_discrete"
SEC_TYPE"0402"
SEC"1"
BOM_COST"P1V538_BMC_STBY_VR"
ROOM"P1V538_BMC_STBY_VR";
"A"
$PN"1"2;
"B"
$PN"2"27;
%"GND"
"1","(9450,3350)","0","mstr_symbols","I62";
;
P1V5_STBY_IBMC_VR""
P1V5_STBY_IBMC""
CDS_LIB"mstr_symbols"
SIZE"1B"
BOM_COST"P1V26_BMC_STBY_VR"
VOLTAGE"0.0V"
ROOM"P1V26_BMC_STBY_VR"
BODY_TYPE"PLUMBING"
HDL_POWER"GND";
"A\NAC"6;
%"P3V3_STBY"
"1","(6525,4625)","0","mstr_symbols","I67";
;
CDS_LIB"mstr_symbols"
SIZE"1B"
VOLTAGE"3.3V"
BODY_TYPE"PLUMBING"
HDL_POWER"P3V3_STBY";
"G\NAC"7;
%"GND"
"1","(7475,3850)","0","mstr_symbols","I69";
;
P1V5_STBY_IBMC_VR""
P1V5_STBY_IBMC""
CDS_LIB"mstr_symbols"
BOM_COST"P1V26_BMC_STBY_VR"
SIZE"1B"
VOLTAGE"0.0V"
ROOM"P1V26_BMC_STBY_VR"
BODY_TYPE"PLUMBING"
HDL_POWER"GND";
"A\NAC"8;
%"CAP"
"1","(11300,3550)","0","mstr_discrete","I7";
;
CDS_SEC"1"
PACK_TYPE"0805LF"
VOLTAGE"4V"
MATERIAL"X6S"
LOCATION"C9F13"
VALUE"22UF"
PART_NUMBER"C95333-002"
TOLERANCE"20%"
CDS_LOCATION"C9F13"
CDS_LIB"mstr_discrete"
SEC"1"
SEC_TYPE"0805LF"
ROOM"P1V538_BMC_STBY_VR"
BOM_COST"P1V538_BMC_STBY_VR";
"A"
$PN"1"19;
"B"
$PN"2"15;
%"RT9059"
"1","(8850,3775)","0","mstr_vreg","I70";
;
CDS_SEC"1"
PART_NUMBER"H65765-001"
LOCATION"EU9F2"
MATERIAL"IC"
CDS_LIB"mstr_vreg"
CDS_LOCATION"EU9F2"
SEC_TYPE"DFN"
SEC"1"
PACK_TYPE"DFN";
"VIN<0>"
$PN"7"7;
"VIN<1>"
$PN"8"7;
"VIN<2>"
$PN"9"7;
"EN"
$PN"6"26;
"VOUT<0>"
$PN"1"19;
"VOUT<1>"
$PN"2"19;
"VOUT<2>"
$PN"3"19;
"GND"
$PN"11"6;
"ADJ_NC"
$PN"4"25;
"VDD"
$PN"10"7;
"PGOOD"
$PN"5"27;
%"CAP_A"
"1","(7475,4125)","0","dev_discrete","I71";
;
LOCATION"C9F5"
VALUE"0.1UF"
VOLTAGE"16V"
PART_NUMBER"A36096-030"
TOLERANCE"10%"
PACK_TYPE"0402V"
MATERIAL"X7R"
CDS_LOCATION"C9F5"
CDS_LIB"dev_discrete"
CDS_SEC"1"
SEC_TYPE"0402V"
SEC"1";
"B"
$PN"2"8;
"A"
$PN"1"7;
%"RES"
"1","(10700,4275)","0","mstr_discrete","I72";
;
CDS_SEC"1"
TOLERANCE"1.0%"
MATERIAL"CHIP"
PACK_TYPE"0402"
PART_NUMBER"G21796-250"
LOCATION"R1T9"
WATTAGE"1/16W"
VALUE"22.1"
CDS_LIB"mstr_discrete"
CDS_LOCATION"R1T9"
SEC_TYPE"0402"
SEC"1"
ROOM"P1V538_BMC_STBY_VR";
"B"
$PN"2"28;
"A"
$PN"1"27;
%"RT9059"
"1","(8425,1700)","0","mstr_vreg","I73";
;
CDS_SEC"1"
$SEC"1"
CDS_LOCATION"EU25F2"
PART_NUMBER"H65765-001"
LOCATION"EU25F2"
MATERIAL"IC"
PACK_TYPE"DFN"
CDS_LIB"mstr_vreg";
"VIN<0>"
$PN"7"10;
"VIN<1>"
$PN"8"10;
"VIN<2>"
$PN"9"10;
"EN"
$PN"6"21;
"VOUT<0>"
$PN"1"18;
"VOUT<1>"
$PN"2"18;
"VOUT<2>"
$PN"3"18;
"GND"
$PN"11"20;
"ADJ_NC"
$PN"4"23;
"VDD"
$PN"10"10;
"PGOOD"
$PN"5"22;
%"GND"
"1","(7050,1775)","0","mstr_symbols","I74";
;
P1V5_STBY_IBMC""
P1V5_STBY_IBMC_VR""
ROOM"P1V26_BMC_STBY_VR"
VOLTAGE"0.0V"
SIZE"1B"
BOM_COST"P1V26_BMC_STBY_VR"
CDS_LIB"mstr_symbols"
BODY_TYPE"PLUMBING"
HDL_POWER"GND";
"A\NAC"9;
%"P3V3_STBY"
"1","(6100,2550)","0","mstr_symbols","I75";
;
VOLTAGE"3.3V"
SIZE"1B"
CDS_LIB"mstr_symbols"
BODY_TYPE"PLUMBING"
HDL_POWER"P3V3_STBY";
"G\NAC"10;
%"RES"
"1","(10275,2200)","0","mstr_discrete","I77";
;
CDS_SEC"1"
$SEC"1"
CDS_LOCATION"R1W9"
PACK_TYPE"0402"
WATTAGE"1/16W"
TOLERANCE"1.0%"
LOCATION"R1W9"
VALUE"22.1"
MATERIAL"CHIP"
PART_NUMBER"G21796-250"
ROOM"P1V538_BMC_STBY_VR"
CDS_LIB"mstr_discrete";
"B"
$PN"2"24;
"A"
$PN"1"22;
%"P3V3_STBY"
"1","(9200,2700)","0","mstr_symbols","I78";
;
SIZE"1B"
VOLTAGE"3.3V"
CDS_LIB"mstr_symbols"
BODY_TYPE"PLUMBING"
HDL_POWER"P3V3_STBY";
"G\NAC"11;
%"RES"
"2","(9200,2450)","0","mstr_discrete","I79";
;
CDS_SEC"1"
$SEC"1"
CDS_LOCATION"R9W12"
LOCATION"R9W12"
P1V5_STBY_IBMC_VR""
P1V5_STBY_IBMC""
VALUE"10.0K"
TOLERANCE"1%"
WATTAGE"1/16W"
MATERIAL"CHIP"
PACK_TYPE"0402"
PART_NUMBER"G21796-016"
ROOM"P1V538_BMC_STBY_VR"
BOM_COST"P1V538_BMC_STBY_VR"
CDS_LIB"mstr_discrete";
"A"
$PN"1"11;
"B"
$PN"2"22;
%"CAP"
"1","(10875,1475)","0","mstr_discrete","I81";
;
CDS_SEC"1"
$SEC"1"
CDS_LOCATION"C9W13"
LOCATION"C9W13"
TOLERANCE"20%"
PART_NUMBER"C95333-002"
MATERIAL"X6S"
PACK_TYPE"0805LF"
VOLTAGE"4V"
VALUE"22UF"
BOM_COST"P1V538_BMC_STBY_VR"
ROOM"P1V538_BMC_STBY_VR"
CDS_LIB"mstr_discrete";
"A"
$PN"1"18;
"B"
$PN"2"12;
%"GND"
"1","(10750,1125)","0","mstr_symbols","I82";
;
P1V5_STBY_IBMC_VR""
P1V5_STBY_IBMC""
ROOM"P1V538_BMC_STBY_VR"
VOLTAGE"0.0V"
SIZE"1B"
BOM_COST"P1V538_BMC_STBY_VR"
CDS_LIB"mstr_symbols"
BODY_TYPE"PLUMBING"
HDL_POWER"GND";
"A\NAC"12;
%"CAP"
"1","(10450,1550)","0","mstr_discrete","I83";
;
CDS_SEC"1"
$SEC"1"
CDS_LOCATION"C1W15"
PACK_TYPE"0603"
PART_NUMBER"E15431-002"
VOLTAGE"6.3V"
TOLERANCE"20%"
MATERIAL"X6S"
VALUE"10UF"
LOCATION"C1W15"
BOM_COST"P1V538_BMC_STBY_VR"
ROOM"P1V538_BMC_STBY_VR"
CDS_LIB"mstr_discrete";
"A"
$PN"1"18;
"B"
$PN"2"12;
%"CAP"
"1","(9950,2075)","0","mstr_discrete","I84";
;
CDS_SEC"1"
$SEC"1"
CDS_LOCATION"C9W10"
MATERIAL"X7R"
TOLERANCE"10%"
PACK_TYPE"0402LF"
LOCATION"C9W10"
VALUE"1000PF"
PART_NUMBER"A36096-046"
ROOM"P1V538_BMC_STBY_VR"
BOM_COST"P1V538_BMC_STBY_VR"
VOLTAGE"50V"
CDS_LIB"mstr_discrete";
"A"
$PN"1"22;
"B"
$PN"2"13;
%"GND"
"1","(9950,1900)","0","mstr_symbols","I85";
;
ROOM"P1V538_BMC_STBY_VR"
VOLTAGE"0.0V"
SIZE"1B"
BOM_COST"P1V538_BMC_STBY_VR"
CDS_LIB"mstr_symbols"
BODY_TYPE"PLUMBING"
HDL_POWER"GND";
"A\NAC"13;
%"RES"
"1","(9925,900)","1","mstr_discrete","I87";
;
CDS_SEC"1"
$SEC"1"
CDS_LOCATION"R9W32"
MATERIAL"CHIP"
P1V5_STBY_IBMC""
P1V5_STBY_IBMC_VR""
TOLERANCE"1.0%"
VALUE"13K"
LOCATION"R9W32"
PACK_TYPE"0402"
PART_NUMBER"G21796-221"
WATTAGE"1/16W"
BOM_COST"P1V538_BMC_STBY_VR"
ROOM"P1V538_BMC_STBY_VR"
CDS_LIB"mstr_discrete";
"B"
$PN"2"23;
"A"
$PN"1"14;
%"GND"
"1","(9925,625)","0","mstr_symbols","I88";
;
P1V5_STBY_IBMC""
P1V5_STBY_IBMC_VR""
BOM_COST"P1V538_BMC_STBY_VR"
SIZE"1B"
VOLTAGE"0.0V"
ROOM"P1V538_BMC_STBY_VR"
CDS_LIB"mstr_symbols"
BODY_TYPE"PLUMBING"
HDL_POWER"GND";
"A\NAC"14;
%"GND"
"1","(9025,1275)","0","mstr_symbols","I89";
;
P1V5_STBY_IBMC""
P1V5_STBY_IBMC_VR""
ROOM"P1V26_BMC_STBY_VR"
VOLTAGE"0.0V"
BOM_COST"P1V26_BMC_STBY_VR"
SIZE"1B"
CDS_LIB"mstr_symbols"
BODY_TYPE"PLUMBING"
HDL_POWER"GND";
"A\NAC"20;
%"GND"
"1","(11175,3200)","0","mstr_symbols","I9";
;
P1V5_STBY_IBMC""
P1V5_STBY_IBMC_VR""
CDS_LIB"mstr_symbols"
BOM_COST"P1V538_BMC_STBY_VR"
SIZE"1B"
VOLTAGE"0.0V"
ROOM"P1V538_BMC_STBY_VR"
BODY_TYPE"PLUMBING"
HDL_POWER"GND";
"A\NAC"15;
%"CAP_A"
"1","(7050,2050)","0","dev_discrete","I90";
;
CDS_SEC"1"
$SEC"1"
CDS_LOCATION"C9W5"
MATERIAL"X7R"
VALUE"0.1UF"
VOLTAGE"16V"
TOLERANCE"10%"
PACK_TYPE"0402V"
PART_NUMBER"A36096-030"
LOCATION"C9W5"
CDS_LIB"dev_discrete";
"B"
$PN"2"9;
"A"
$PN"1"10;
%"CAP"
"1","(6625,1225)","2","mstr_discrete","I91";
;
CDS_SEC"1"
$SEC"1"
CDS_LOCATION"C9W6"
PART_NUMBER"A36096-046"
PACK_TYPE"0402LF"
TOLERANCE"10%"
VOLTAGE"50V"
MATERIAL"EMPTY"
VALUE"1000PF"
LOCATION"C9W6"
BOM_COST"P1V538_BMC_STBY_VR"
ROOM"P1V538_BMC_STBY_VR"
CDS_LIB"mstr_discrete";
"A"
$PN"1"21;
"B"
$PN"2"17;
%"CAP"
"1","(6100,2075)","0","mstr_discrete","I92";
;
CDS_SEC"1"
$SEC"1"
CDS_LOCATION"C1W7"
LOCATION"C1W7"
PART_NUMBER"E15431-002"
VALUE"10UF"
MATERIAL"X6S"
TOLERANCE"20%"
VOLTAGE"6.3V"
PACK_TYPE"0603"
BOM_COST"P1V538_BMC_STBY_VR"
ROOM"P1V538_BMC_STBY_VR"
CDS_LIB"mstr_discrete";
"A"
$PN"1"10;
"B"
$PN"2"16;
%"GND"
"1","(6100,1775)","0","mstr_symbols","I93";
;
VOLTAGE"0.0V"
SIZE"1B"
CDS_LIB"mstr_symbols"
BODY_TYPE"PLUMBING"
HDL_POWER"GND";
"A\NAC"16;
%"GND"
"1","(6625,800)","0","mstr_symbols","I95";
;
P1V5_STBY_IBMC_VR""
P1V5_STBY_IBMC""
ROOM"P1V538_BMC_STBY_VR"
SIZE"1B"
VOLTAGE"0.0V"
BOM_COST"P1V538_BMC_STBY_VR"
CDS_LIB"mstr_symbols"
BODY_TYPE"PLUMBING"
HDL_POWER"GND";
"A\NAC"17;
%"W_VCC_CIRCLE"
"1","(11300,1900)","0","w_power","I96";
;
HDL_POWER"P2V5_AUX_BMC"
CDS_LIB"w_power"
CDS_LMAN_SYM_OUTLINE"-100,100,100,-100"
BODY_TYPE"PLUMBING";
"VCC_CIRCLE \B"18;
%"W_VCC_CIRCLE"
"1","(11725,3975)","0","w_power","I97";
;
HDL_POWER"P1V2_AUX_BMC"
CDS_LMAN_SYM_OUTLINE"-100,100,100,-100"
CDS_LIB"w_power"
BODY_TYPE"PLUMBING";
"VCC_CIRCLE \B"19;
%"5K1R2F-2-GP"
"1","(10350,3525)","0","w_hdl","I98";
;
CDS_SEC"1"
$SEC"1"
CDS_LOCATION"R9F31"
VALUE"5K1R2F-2-GP"
LOCATION"R9F31"
PACK_TYPE"SMD-RG"
PART_NUMBER"64.51015.6DL"
CDS_LIB"w_hdl"
CDS_LMAN_SYM_OUTLINE"-50,75,50,-75";
"2"
$PN"2"25;
"1"
$PN"1"19;
%"21K5R2F-GP"
"1","(9925,1325)","0","w_hdl","I99";
;
CDS_SEC"1"
$SEC"1"
CDS_LOCATION"R9W31"
LOCATION"R9W31"
VALUE"21K5R2F-GP"
PACK_TYPE"RCL_GP"
PART_NUMBER"64.21525.6DL"
CDS_LIB"w_hdl"
CDS_LMAN_SYM_OUTLINE"-50,75,50,-75";
"2"
$PN"2"23;
"1"
$PN"1"18;
END.
